FILE_TYPE = MULTI_PHYS_TABLE;

PART 'AP2205W57'

{========================================================================================}
:VALUE         | PART_TYPE | MATERIAL | PART_NUMBER    = STANDARD    | LIFECYCLE     | PART_NUMBER   | JEDEC_TYPE              | DESCRIPTION                      | MANUFTR | MANUF_PN      | RD_CMPLS_LVL | CMPLS_LVL | FROM_PJ      | CLASS | DIP_SMD | DATA                  | EE_CHECK_LIST | FP_ECN | PSL | CREATOR | STATUS | MSD       | ESD_CDM | ESD_HBM | ESD_MM | PIN_LENGTH_SHORT_PIN | PIN_LENGTH_LONG_PIN | CREATEDAY  ;
{========================================================================================}
 'AP2205-W5-7' | 'SMLF'    | 'IC'     | 'AL002205001'(!) = ''               | ''               | 'AL002205001' |'SOT25-5_0-95_2-96X1-6'| 'IC OTHER(5P)AP2205-W5-7(SOT25)' | 'DDS'   | 'AP2205-W5-7' | 'EP(V1)'     | ''        | 'IXH-WISELY' | 'IC'  | ''      | 'DDS_AP2205-W5-7.pdf' | ''            | ''     | ''  | ''      | ''     | 'Level-1' | '1000'  | '2000'  | 'NA'   | '0 MILS'             | '0 MILS'            | '20200206'
 'AP2205-W5-7' | 'SMLF'    | 'EMPTY'  | 'AL002205001'(!) = ''               | ''               | 'AL002205001' |'SOT25-5_0-95_2-96X1-6'| 'IC OTHER(5P)AP2205-W5-7(SOT25)' | 'DDS'   | 'AP2205-W5-7' | 'EP(V1)'     | ''        | 'IXH-WISELY' | 'IC'  | ''      | 'DDS_AP2205-W5-7.pdf' | ''            | ''     | ''  | ''      | ''     | 'Level-1' | '1000'  | '2000'  | 'NA'   | '0 MILS'             | '0 MILS'            | '20200206'

END_PART

END.

